# BASEBOARD_FAB2 (Tioga Pass) — schematic netlist excerpt (pin names and nets, part order shuffled) for the footprints in the layout excerpt that follows; sources: Cadence DE-HDL packaged netlist, KiCad conversion of Wiwynn_Tioga_Pass_MB.brd

C7E9  CAP_A  0.1UF 16V 10% X7R  pkg 0402V  page 198 : A = P12V ; B = GND
CT63  CAP_A  0.1UF 16V 10% X7R  pkg 0402V  page 214 : A = VR_PVCCIO_CPU1_AIREF1 ; B = GND

(kicad_pcb
	(version 20260206)
	(generator "pcbnew")
	(generator_version "10.0")
	(general
		(thickness 1.6)
		(legacy_teardrops no)
	)
	(paper "A4")
	(title_block
		(title "Wiwynn_Tioga_Pass_MB.brd")
		(comment 1 "Tioga Pass / footprints 750-751 of 4770")
	)
	(layers
		(0 "F.Cu" signal "TOP")
		(4 "In1.Cu" signal "L2GND")
		(6 "In2.Cu" signal "L3")
		(8 "In3.Cu" signal "L4GND")
		(10 "In4.Cu" signal "L5")
		(12 "In5.Cu" signal "L6GND")
		(14 "In6.Cu" signal "L7VCC")
		(16 "In7.Cu" signal "L8VCC")
		(18 "In8.Cu" signal "L9GND")
		(20 "In9.Cu" signal "L10")
		(22 "In10.Cu" signal "L11GND")
		(24 "In11.Cu" signal "L12")
		(26 "In12.Cu" signal "L13GND")
		(2 "B.Cu" signal "BOTTOM")
		(9 "F.Adhes" user "F.Adhesive")
		(11 "B.Adhes" user "B.Adhesive")
		(13 "F.Paste" user "Package Geometry/Pastemask Top")
		(15 "B.Paste" user "Package Geometry/Pastemask Bottom")
		(5 "F.SilkS" user "Ref Des/Silkscreen Top")
		(7 "B.SilkS" user "Ref Des/Silkscreen Bottom")
		(1 "F.Mask" user "Board Geometry/Soldermask Top")
		(3 "B.Mask" user "Board Geometry/Soldermask Bottom")
		(17 "Dwgs.User" user "User.Drawings")
		(19 "Cmts.User" user "User.Comments")
		(21 "Eco1.User" user "User.Eco1")
		(23 "Eco2.User" user "User.Eco2")
		(25 "Edge.Cuts" user "Board Geometry/Outline")
		(27 "Margin" user)
		(31 "F.CrtYd" user "Package Geometry/Place Bound Top")
		(29 "B.CrtYd" user "Package Geometry/Place Bound Bottom")
		(35 "F.Fab" user "Ref Des/Assembly Top")
		(33 "B.Fab" user "Ref Des/Assembly Bottom")
	)
	(footprint ""
		(layer "F.Cu")
		(at 497.120926 -20.703286 90)
		(property "Reference" "C7E9"
			(at 0 0 90)
			(layer "F.SilkS")
			(hide yes)
			(effects
				(font
					(size 1.27 1.27)
				)
			)
		)
		(property "Value" ""
			(at 0 0 90)
			(layer "F.Fab")
			(effects
				(font
					(size 1.27 1.27)
				)
			)
		)
		(duplicate_pad_numbers_are_jumpers no)
		(fp_rect
			(start 0.3048 0.9906)
			(end -0.3048 -0.1016)
			(stroke
				(width 0)
				(type default)
			)
			(fill no)
			(layer "F.CrtYd")
		)
		(fp_line
			(start 0.3048 -0.1016)
			(end -0.3048 -0.1016)
			(stroke
				(width 0.1)
				(type default)
			)
			(layer "F.Fab")
		)
		(fp_line
			(start -0.3048 -0.1016)
			(end -0.3048 0.9906)
			(stroke
				(width 0.1)
				(type default)
			)
			(layer "F.Fab")
		)
		(fp_line
			(start 0.3048 0.9906)
			(end 0.3048 -0.1016)
			(stroke
				(width 0.1)
				(type default)
			)
			(layer "F.Fab")
		)
		(fp_line
			(start -0.3048 0.9906)
			(end 0.3048 0.9906)
			(stroke
				(width 0.1)
				(type default)
			)
			(layer "F.Fab")
		)
		(pad "1" smd rect
			(at 0 0 90)
			(size 0.508 0.508)
			(layers "F.Cu" "F.Mask" "F.Paste")
			(net "P12V")
		)
		(pad "2" smd rect
			(at 0 0.889 90)
			(size 0.508 0.508)
			(layers "F.Cu" "F.Mask" "F.Paste")
			(net "GND")
		)
		(zone
			(layer "F.Cu")
			(hatch none 0.5)
			(connect_pads
				(clearance 0)
			)
			(min_thickness 0.25)
			(keepout
				(tracks allowed)
				(vias not_allowed)
				(pads allowed)
				(copperpour not_allowed)
				(footprints allowed)
			)
			(placement
				(enabled no)
				(sheetname "")
			)
			(fill
				(thermal_gap 0.5)
				(thermal_bridge_width 0.5)
				(island_removal_mode 0)
			)
			(polygon
				(pts
					(xy 497.755926 -20.957286) (xy 497.374926 -20.957286) (xy 497.374926 -20.449286) (xy 497.755926 -20.449286)
				)
			)
		)
		(zone
			(layer "F.Cu")
			(hatch none 0.5)
			(connect_pads
				(clearance 0)
			)
			(min_thickness 0.25)
			(keepout
				(tracks not_allowed)
				(vias allowed)
				(pads allowed)
				(copperpour not_allowed)
				(footprints allowed)
			)
			(placement
				(enabled no)
				(sheetname "")
			)
			(fill
				(thermal_gap 0.5)
				(thermal_bridge_width 0.5)
				(island_removal_mode 0)
			)
			(polygon
				(pts
					(xy 497.755926 -20.957286) (xy 497.374926 -20.957286) (xy 497.374926 -20.449286) (xy 497.755926 -20.449286)
				)
			)
		)
	)
	(footprint ""
		(layer "F.Cu")
		(at 181.8132 -57.785 -90)
		(property "Reference" "CT63"
			(at -1.19253 2.8956 0)
			(unlocked yes)
			(layer "F.SilkS")
			(effects
				(font
					(size 0.7874 0.5842)
					(thickness 0.1524)
				)
				(justify left)
			)
		)
		(property "Value" ""
			(at 0 0 270)
			(layer "F.Fab")
			(effects
				(font
					(size 1.27 1.27)
				)
			)
		)
		(duplicate_pad_numbers_are_jumpers no)
		(fp_poly
			(pts
				(xy 0.3048 -0.1016) (xy 0.3048 0.9906) (xy -0.3048 0.9906) (xy -0.3048 -0.1016)
			)
			(stroke
				(width 0)
				(type default)
			)
			(fill no)
			(layer "F.CrtYd")
		)
		(fp_line
			(start -0.3048 0.9906)
			(end 0.3048 0.9906)
			(stroke
				(width 0.1)
				(type default)
			)
			(layer "F.Fab")
		)
		(fp_line
			(start 0.3048 0.9906)
			(end 0.3048 -0.1016)
			(stroke
				(width 0.1)
				(type default)
			)
			(layer "F.Fab")
		)
		(fp_line
			(start -0.3048 -0.1016)
			(end -0.3048 0.9906)
			(stroke
				(width 0.1)
				(type default)
			)
			(layer "F.Fab")
		)
		(fp_line
			(start 0.3048 -0.1016)
			(end -0.3048 -0.1016)
			(stroke
				(width 0.1)
				(type default)
			)
			(layer "F.Fab")
		)
		(pad "1" smd rect
			(at 0 0 270)
			(size 0.508 0.508)
			(layers "F.Cu" "F.Mask" "F.Paste")
			(net "VR_PVCCIO_CPU1_AIREF1")
		)
		(pad "2" smd rect
			(at 0 0.889 270)
			(size 0.508 0.508)
			(layers "F.Cu" "F.Mask" "F.Paste")
			(net "GND")
		)
		(zone
			(layer "F.Cu")
			(hatch none 0.5)
			(connect_pads
				(clearance 0)
			)
			(min_thickness 0.25)
			(keepout
				(tracks not_allowed)
				(vias allowed)
				(pads allowed)
				(copperpour not_allowed)
				(footprints allowed)
			)
			(placement
				(enabled no)
				(sheetname "")
			)
			(fill
				(thermal_gap 0.5)
				(thermal_bridge_width 0.5)
				(island_removal_mode 0)
			)
			(polygon
				(pts
					(xy 181.1782 -58.039) (xy 181.1782 -57.531) (xy 181.5592 -57.531) (xy 181.5592 -58.039)
				)
			)
		)
		(zone
			(layer "F.Cu")
			(hatch none 0.5)
			(connect_pads
				(clearance 0)
			)
			(min_thickness 0.25)
			(keepout
				(tracks allowed)
				(vias not_allowed)
				(pads allowed)
				(copperpour not_allowed)
				(footprints allowed)
			)
			(placement
				(enabled no)
				(sheetname "")
			)
			(fill
				(thermal_gap 0.5)
				(thermal_bridge_width 0.5)
				(island_removal_mode 0)
			)
			(polygon
				(pts
					(xy 181.5592 -58.039) (xy 181.5592 -57.531) (xy 181.1782 -57.531) (xy 181.1782 -58.039)
				)
			)
		)
	)
)
